(kicad_pcb
	(version 20260206)
	(generator "pcbnew")
	(generator_version "10.0")
	(general
		(thickness 1.6)
		(legacy_teardrops no)
	)
	(paper "A4")
	(title_block
		(title "04192023_DAF0TMB3IC0_F0TG_MB_C_brd_V02_OCP.brd")
		(comment 1 "Grand Teton / footprints 1362-1367 of 8354")
	)
	(layers
		(0 "F.Cu" signal "TOP")
		(4 "In1.Cu" signal "GND")
		(6 "In2.Cu" signal "IN1")
		(8 "In3.Cu" signal "GND1")
		(10 "In4.Cu" signal "IN2")
		(12 "In5.Cu" signal "GND2")
		(14 "In6.Cu" signal "IN3")
		(16 "In7.Cu" signal "GND3")
		(18 "In8.Cu" signal "VCC")
		(20 "In9.Cu" signal "VCC1")
		(22 "In10.Cu" signal "GND4")
		(24 "In11.Cu" signal "IN4")
		(26 "In12.Cu" signal "GND5")
		(28 "In13.Cu" signal "IN5")
		(30 "In14.Cu" signal "GND6")
		(32 "In15.Cu" signal "IN6")
		(34 "In16.Cu" signal "GND7")
		(2 "B.Cu" signal "BOTTOM")
		(9 "F.Adhes" user "F.Adhesive")
		(11 "B.Adhes" user "B.Adhesive")
		(13 "F.Paste" user "Package Geometry/Pastemask Top")
		(15 "B.Paste" user "Package Geometry/Pastemask Bottom")
		(5 "F.SilkS" user "Ref Des/Silkscreen Top")
		(7 "B.SilkS" user "Ref Des/Silkscreen Bottom")
		(1 "F.Mask" user "Board Geometry/Soldermask Top")
		(3 "B.Mask" user "Board Geometry/Soldermask Bottom")
		(17 "Dwgs.User" user "User.Drawings")
		(19 "Cmts.User" user "User.Comments")
		(21 "Eco1.User" user "User.Eco1")
		(23 "Eco2.User" user "User.Eco2")
		(25 "Edge.Cuts" user "Board Geometry/Outline")
		(27 "Margin" user)
		(31 "F.CrtYd" user "Package Geometry/Place Bound Top")
		(29 "B.CrtYd" user "Package Geometry/Place Bound Bottom")
		(35 "F.Fab" user "Ref Des/Assembly Top")
		(33 "B.Fab" user "Ref Des/Assembly Bottom")
	)
	(footprint ""
		(layer "F.Cu")
		(at 419.58514 -58.797698 90)
		(property "Reference" "C1874"
			(at 0 0 90)
			(layer "F.SilkS")
			(hide yes)
			(effects
				(font
					(size 1.27 1.27)
				)
			)
		)
		(property "Value" ""
			(at 0 0 90)
			(layer "F.Fab")
			(effects
				(font
					(size 1.27 1.27)
				)
			)
		)
		(duplicate_pad_numbers_are_jumpers no)
		(fp_line
			(start 0.7874 -0.4064)
			(end 0.7874 0.4064)
			(stroke
				(width 0.1524)
				(type default)
			)
			(layer "F.SilkS")
		)
		(fp_line
			(start -0.7874 -0.4064)
			(end 0.7874 -0.4064)
			(stroke
				(width 0.1524)
				(type default)
			)
			(layer "F.SilkS")
		)
		(fp_line
			(start 0.7874 0.4064)
			(end -0.7874 0.4064)
			(stroke
				(width 0.1524)
				(type default)
			)
			(layer "F.SilkS")
		)
		(fp_line
			(start -0.7874 0.4064)
			(end -0.7874 -0.4064)
			(stroke
				(width 0.1524)
				(type default)
			)
			(layer "F.SilkS")
		)
		(fp_line
			(start -0.12065 -0.305054)
			(end -0.12065 -0.2794)
			(stroke
				(width 0.1)
				(type default)
			)
			(layer "F.Fab")
		)
		(fp_line
			(start -0.67945 -0.305054)
			(end -0.12065 -0.305054)
			(stroke
				(width 0.1)
				(type default)
			)
			(layer "F.Fab")
		)
		(fp_line
			(start 0.67945 -0.3048)
			(end 0.67945 0.3048)
			(stroke
				(width 0.1)
				(type default)
			)
			(layer "F.Fab")
		)
		(fp_line
			(start 0.12065 -0.3048)
			(end 0.67945 -0.3048)
			(stroke
				(width 0.1)
				(type default)
			)
			(layer "F.Fab")
		)
		(fp_line
			(start 0.12065 -0.2794)
			(end 0.12065 -0.3048)
			(stroke
				(width 0.1)
				(type default)
			)
			(layer "F.Fab")
		)
		(fp_line
			(start -0.12065 -0.2794)
			(end 0.12065 -0.2794)
			(stroke
				(width 0.1)
				(type default)
			)
			(layer "F.Fab")
		)
		(fp_line
			(start 0.120396 0.2794)
			(end -0.12065 0.2794)
			(stroke
				(width 0.1)
				(type default)
			)
			(layer "F.Fab")
		)
		(fp_line
			(start -0.12065 0.2794)
			(end -0.12065 0.3048)
			(stroke
				(width 0.1)
				(type default)
			)
			(layer "F.Fab")
		)
		(fp_line
			(start 0.67945 0.3048)
			(end 0.120396 0.3048)
			(stroke
				(width 0.1)
				(type default)
			)
			(layer "F.Fab")
		)
		(fp_line
			(start 0.120396 0.3048)
			(end 0.120396 0.2794)
			(stroke
				(width 0.1)
				(type default)
			)
			(layer "F.Fab")
		)
		(fp_line
			(start -0.12065 0.3048)
			(end -0.67945 0.3048)
			(stroke
				(width 0.1)
				(type default)
			)
			(layer "F.Fab")
		)
		(fp_line
			(start -0.67945 0.3048)
			(end -0.67945 -0.305054)
			(stroke
				(width 0.1)
				(type default)
			)
			(layer "F.Fab")
		)
		(pad "1" smd circle
			(at -0.40005 0 90)
			(size 0 0)
			(layers "F.Cu" "F.Mask" "F.Paste")
			(net "P3V3_AUX")
		)
		(pad "2" smd circle
			(at 0.40005 0 90)
			(size 0 0)
			(layers "F.Cu" "F.Mask" "F.Paste")
			(net "GND")
		)
	)
	(footprint ""
		(layer "F.Cu")
		(at 205.365604 -342.075262 -90)
		(property "Reference" "PR455"
			(at 0 0 270)
			(layer "F.SilkS")
			(hide yes)
			(effects
				(font
					(size 1.27 1.27)
				)
			)
		)
		(property "Value" ""
			(at 0 0 270)
			(layer "F.Fab")
			(effects
				(font
					(size 1.27 1.27)
				)
			)
		)
		(duplicate_pad_numbers_are_jumpers no)
		(fp_line
			(start -0.7874 0.4064)
			(end -0.7874 -0.4064)
			(stroke
				(width 0.1524)
				(type default)
			)
			(layer "F.SilkS")
		)
		(fp_line
			(start 0.7874 0.4064)
			(end -0.7874 0.4064)
			(stroke
				(width 0.1524)
				(type default)
			)
			(layer "F.SilkS")
		)
		(fp_line
			(start -0.7874 -0.4064)
			(end 0.7874 -0.4064)
			(stroke
				(width 0.1524)
				(type default)
			)
			(layer "F.SilkS")
		)
		(fp_line
			(start 0.7874 -0.4064)
			(end 0.7874 0.4064)
			(stroke
				(width 0.1524)
				(type default)
			)
			(layer "F.SilkS")
		)
		(fp_line
			(start -0.67945 0.3048)
			(end -0.67945 -0.305054)
			(stroke
				(width 0.1)
				(type default)
			)
			(layer "F.Fab")
		)
		(fp_line
			(start -0.12065 0.3048)
			(end -0.67945 0.3048)
			(stroke
				(width 0.1)
				(type default)
			)
			(layer "F.Fab")
		)
		(fp_line
			(start 0.120396 0.3048)
			(end 0.120396 0.2794)
			(stroke
				(width 0.1)
				(type default)
			)
			(layer "F.Fab")
		)
		(fp_line
			(start 0.67945 0.3048)
			(end 0.120396 0.3048)
			(stroke
				(width 0.1)
				(type default)
			)
			(layer "F.Fab")
		)
		(fp_line
			(start -0.12065 0.2794)
			(end -0.12065 0.3048)
			(stroke
				(width 0.1)
				(type default)
			)
			(layer "F.Fab")
		)
		(fp_line
			(start 0.120396 0.2794)
			(end -0.12065 0.2794)
			(stroke
				(width 0.1)
				(type default)
			)
			(layer "F.Fab")
		)
		(fp_line
			(start -0.12065 -0.2794)
			(end 0.12065 -0.2794)
			(stroke
				(width 0.1)
				(type default)
			)
			(layer "F.Fab")
		)
		(fp_line
			(start 0.12065 -0.2794)
			(end 0.12065 -0.3048)
			(stroke
				(width 0.1)
				(type default)
			)
			(layer "F.Fab")
		)
		(fp_line
			(start 0.12065 -0.3048)
			(end 0.67945 -0.3048)
			(stroke
				(width 0.1)
				(type default)
			)
			(layer "F.Fab")
		)
		(fp_line
			(start 0.67945 -0.3048)
			(end 0.67945 0.3048)
			(stroke
				(width 0.1)
				(type default)
			)
			(layer "F.Fab")
		)
		(fp_line
			(start -0.67945 -0.305054)
			(end -0.12065 -0.305054)
			(stroke
				(width 0.1)
				(type default)
			)
			(layer "F.Fab")
		)
		(fp_line
			(start -0.12065 -0.305054)
			(end -0.12065 -0.2794)
			(stroke
				(width 0.1)
				(type default)
			)
			(layer "F.Fab")
		)
		(pad "1" smd circle
			(at -0.40005 0 270)
			(size 0 0)
			(layers "F.Cu" "F.Mask" "F.Paste")
			(net "PVDD_33_S5_FB")
		)
		(pad "2" smd circle
			(at 0.40005 0 270)
			(size 0 0)
			(layers "F.Cu" "F.Mask" "F.Paste")
			(net "PVDD_33_S5")
		)
	)
	(footprint ""
		(layer "F.Cu")
		(at 164.283136 -423.816526 -90)
		(property "Reference" "U20"
			(at -0.383286 -3.052826 90)
			(unlocked yes)
			(layer "F.SilkS")
			(effects
				(font
					(size 0.7874 0.5842)
					(thickness 0.1524)
				)
				(justify left)
			)
		)
		(property "Value" ""
			(at 0 0 270)
			(layer "F.Fab")
			(effects
				(font
					(size 1.27 1.27)
				)
			)
		)
		(duplicate_pad_numbers_are_jumpers no)
		(fp_line
			(start -1.8288 2.500122)
			(end 1.8288 2.500122)
			(stroke
				(width 0.1524)
				(type default)
			)
			(layer "F.SilkS")
		)
		(fp_line
			(start 1.8288 2.500122)
			(end 1.8288 -2.500122)
			(stroke
				(width 0.1524)
				(type default)
			)
			(layer "F.SilkS")
		)
		(fp_line
			(start 0 -1.4224)
			(end -1.077722 -2.500122)
			(stroke
				(width 0.1524)
				(type default)
			)
			(layer "F.SilkS")
		)
		(fp_line
			(start -1.8288 -2.500122)
			(end -1.8288 2.500122)
			(stroke
				(width 0.1524)
				(type default)
			)
			(layer "F.SilkS")
		)
		(fp_line
			(start -1.077722 -2.500122)
			(end -1.8288 -2.500122)
			(stroke
				(width 0.1524)
				(type default)
			)
			(layer "F.SilkS")
		)
		(fp_line
			(start 1.077722 -2.500122)
			(end 0 -1.4224)
			(stroke
				(width 0.1524)
				(type default)
			)
			(layer "F.SilkS")
		)
		(fp_line
			(start 1.8288 -2.500122)
			(end 1.077722 -2.500122)
			(stroke
				(width 0.1524)
				(type default)
			)
			(layer "F.SilkS")
		)
		(fp_poly
			(pts
				(xy -3.64236 -3.590036) (xy -4.309364 -2.823718) (xy -3.209544 -2.54)
			)
			(stroke
				(width 0)
				(type default)
			)
			(fill yes)
			(layer "F.SilkS")
		)
		(fp_line
			(start -1.999996 2.500122)
			(end 1.999996 2.500122)
			(stroke
				(width 0.1)
				(type default)
			)
			(layer "F.Fab")
		)
		(fp_line
			(start 1.999996 2.500122)
			(end 1.999996 -2.500122)
			(stroke
				(width 0.1)
				(type default)
			)
			(layer "F.Fab")
		)
		(fp_line
			(start -1.999996 -2.500122)
			(end -1.999996 2.500122)
			(stroke
				(width 0.1)
				(type default)
			)
			(layer "F.Fab")
		)
		(fp_line
			(start 1.999996 -2.500122)
			(end -1.999996 -2.500122)
			(stroke
				(width 0.1)
				(type default)
			)
			(layer "F.Fab")
		)
		(fp_poly
			(pts
				(xy -4.5085 -2.413) (xy -4.5085 -1.397) (xy -3.4925 -1.905)
			)
			(stroke
				(width 0)
				(type default)
			)
			(fill yes)
			(layer "F.Fab")
		)
		(pad "1" smd rect
			(at -2.599944 -1.905 180)
			(size 0.889 1.27)
			(layers "F.Cu" "F.Mask" "F.Paste")
			(net "Net_10835")
		)
		(pad "2" smd rect
			(at -2.599944 -0.635 180)
			(size 0.889 1.27)
			(layers "F.Cu" "F.Mask" "F.Paste")
			(net "Net_10834")
		)
		(pad "3" smd rect
			(at -2.599944 0.635 180)
			(size 0.889 1.27)
			(layers "F.Cu" "F.Mask" "F.Paste")
			(net "U20_E2")
		)
		(pad "4" smd rect
			(at -2.599944 1.905 180)
			(size 0.889 1.27)
			(layers "F.Cu" "F.Mask" "F.Paste")
			(net "GND")
		)
		(pad "5" smd rect
			(at 2.599944 1.905 180)
			(size 0.889 1.27)
			(layers "F.Cu" "F.Mask" "F.Paste")
			(net "SMB_RT_CPU1_P2_ROM_SDA")
		)
		(pad "6" smd rect
			(at 2.599944 0.635 180)
			(size 0.889 1.27)
			(layers "F.Cu" "F.Mask" "F.Paste")
			(net "SMB_RT_CPU1_P2_ROM_SCL")
		)
		(pad "7" smd rect
			(at 2.599944 -0.635 180)
			(size 0.889 1.27)
			(layers "F.Cu" "F.Mask" "F.Paste")
			(net "GND")
		)
		(pad "8" smd rect
			(at 2.599944 -1.905 180)
			(size 0.889 1.27)
			(layers "F.Cu" "F.Mask" "F.Paste")
			(net "P1V8_CPU1_RT_1D")
		)
	)
	(footprint ""
		(layer "F.Cu")
		(at 134.189216 -53.974238 -90)
		(property "Reference" "R1637"
			(at 0 0 270)
			(layer "F.SilkS")
			(hide yes)
			(effects
				(font
					(size 1.27 1.27)
				)
			)
		)
		(property "Value" ""
			(at 0 0 270)
			(layer "F.Fab")
			(effects
				(font
					(size 1.27 1.27)
				)
			)
		)
		(duplicate_pad_numbers_are_jumpers no)
		(fp_line
			(start -0.7874 0.4064)
			(end -0.7874 -0.4064)
			(stroke
				(width 0.1524)
				(type default)
			)
			(layer "F.SilkS")
		)
		(fp_line
			(start 0.7874 0.4064)
			(end -0.7874 0.4064)
			(stroke
				(width 0.1524)
				(type default)
			)
			(layer "F.SilkS")
		)
		(fp_line
			(start -0.7874 -0.4064)
			(end 0.7874 -0.4064)
			(stroke
				(width 0.1524)
				(type default)
			)
			(layer "F.SilkS")
		)
		(fp_line
			(start 0.7874 -0.4064)
			(end 0.7874 0.4064)
			(stroke
				(width 0.1524)
				(type default)
			)
			(layer "F.SilkS")
		)
		(fp_line
			(start -0.67945 0.3048)
			(end -0.67945 -0.305054)
			(stroke
				(width 0.1)
				(type default)
			)
			(layer "F.Fab")
		)
		(fp_line
			(start -0.12065 0.3048)
			(end -0.67945 0.3048)
			(stroke
				(width 0.1)
				(type default)
			)
			(layer "F.Fab")
		)
		(fp_line
			(start 0.120396 0.3048)
			(end 0.120396 0.2794)
			(stroke
				(width 0.1)
				(type default)
			)
			(layer "F.Fab")
		)
		(fp_line
			(start 0.67945 0.3048)
			(end 0.120396 0.3048)
			(stroke
				(width 0.1)
				(type default)
			)
			(layer "F.Fab")
		)
		(fp_line
			(start -0.12065 0.2794)
			(end -0.12065 0.3048)
			(stroke
				(width 0.1)
				(type default)
			)
			(layer "F.Fab")
		)
		(fp_line
			(start 0.120396 0.2794)
			(end -0.12065 0.2794)
			(stroke
				(width 0.1)
				(type default)
			)
			(layer "F.Fab")
		)
		(fp_line
			(start -0.12065 -0.2794)
			(end 0.12065 -0.2794)
			(stroke
				(width 0.1)
				(type default)
			)
			(layer "F.Fab")
		)
		(fp_line
			(start 0.12065 -0.2794)
			(end 0.12065 -0.3048)
			(stroke
				(width 0.1)
				(type default)
			)
			(layer "F.Fab")
		)
		(fp_line
			(start 0.12065 -0.3048)
			(end 0.67945 -0.3048)
			(stroke
				(width 0.1)
				(type default)
			)
			(layer "F.Fab")
		)
		(fp_line
			(start 0.67945 -0.3048)
			(end 0.67945 0.3048)
			(stroke
				(width 0.1)
				(type default)
			)
			(layer "F.Fab")
		)
		(fp_line
			(start -0.67945 -0.305054)
			(end -0.12065 -0.305054)
			(stroke
				(width 0.1)
				(type default)
			)
			(layer "F.Fab")
		)
		(fp_line
			(start -0.12065 -0.305054)
			(end -0.12065 -0.2794)
			(stroke
				(width 0.1)
				(type default)
			)
			(layer "F.Fab")
		)
		(pad "1" smd circle
			(at -0.40005 0 270)
			(size 0 0)
			(layers "F.Cu" "F.Mask" "F.Paste")
			(net "U152_OE_N")
		)
		(pad "2" smd circle
			(at 0.40005 0 270)
			(size 0 0)
			(layers "F.Cu" "F.Mask" "F.Paste")
			(net "GND")
		)
	)
	(footprint ""
		(layer "F.Cu")
		(at 200.600564 -71.582788)
		(property "Reference" "PC2201"
			(at 0 0 0)
			(layer "F.SilkS")
			(hide yes)
			(effects
				(font
					(size 1.27 1.27)
				)
			)
		)
		(property "Value" ""
			(at 0 0 0)
			(layer "F.Fab")
			(effects
				(font
					(size 1.27 1.27)
				)
			)
		)
		(duplicate_pad_numbers_are_jumpers no)
		(fp_line
			(start -0.7874 -0.4064)
			(end 0.7874 -0.4064)
			(stroke
				(width 0.1524)
				(type default)
			)
			(layer "F.SilkS")
		)
		(fp_line
			(start -0.7874 0.4064)
			(end -0.7874 -0.4064)
			(stroke
				(width 0.1524)
				(type default)
			)
			(layer "F.SilkS")
		)
		(fp_line
			(start 0.7874 -0.4064)
			(end 0.7874 0.4064)
			(stroke
				(width 0.1524)
				(type default)
			)
			(layer "F.SilkS")
		)
		(fp_line
			(start 0.7874 0.4064)
			(end -0.7874 0.4064)
			(stroke
				(width 0.1524)
				(type default)
			)
			(layer "F.SilkS")
		)
		(fp_line
			(start -0.67945 -0.305054)
			(end -0.12065 -0.305054)
			(stroke
				(width 0.1)
				(type default)
			)
			(layer "F.Fab")
		)
		(fp_line
			(start -0.67945 0.3048)
			(end -0.67945 -0.305054)
			(stroke
				(width 0.1)
				(type default)
			)
			(layer "F.Fab")
		)
		(fp_line
			(start -0.12065 -0.305054)
			(end -0.12065 -0.2794)
			(stroke
				(width 0.1)
				(type default)
			)
			(layer "F.Fab")
		)
		(fp_line
			(start -0.12065 -0.2794)
			(end 0.12065 -0.2794)
			(stroke
				(width 0.1)
				(type default)
			)
			(layer "F.Fab")
		)
		(fp_line
			(start -0.12065 0.2794)
			(end -0.12065 0.3048)
			(stroke
				(width 0.1)
				(type default)
			)
			(layer "F.Fab")
		)
		(fp_line
			(start -0.12065 0.3048)
			(end -0.67945 0.3048)
			(stroke
				(width 0.1)
				(type default)
			)
			(layer "F.Fab")
		)
		(fp_line
			(start 0.120396 0.2794)
			(end -0.12065 0.2794)
			(stroke
				(width 0.1)
				(type default)
			)
			(layer "F.Fab")
		)
		(fp_line
			(start 0.120396 0.3048)
			(end 0.120396 0.2794)
			(stroke
				(width 0.1)
				(type default)
			)
			(layer "F.Fab")
		)
		(fp_line
			(start 0.12065 -0.3048)
			(end 0.67945 -0.3048)
			(stroke
				(width 0.1)
				(type default)
			)
			(layer "F.Fab")
		)
		(fp_line
			(start 0.12065 -0.2794)
			(end 0.12065 -0.3048)
			(stroke
				(width 0.1)
				(type default)
			)
			(layer "F.Fab")
		)
		(fp_line
			(start 0.67945 -0.3048)
			(end 0.67945 0.3048)
			(stroke
				(width 0.1)
				(type default)
			)
			(layer "F.Fab")
		)
		(fp_line
			(start 0.67945 0.3048)
			(end 0.120396 0.3048)
			(stroke
				(width 0.1)
				(type default)
			)
			(layer "F.Fab")
		)
		(pad "1" smd circle
			(at -0.40005 0)
			(size 0 0)
			(layers "F.Cu" "F.Mask" "F.Paste")
			(net "P3V3_E1S_DVDT_0")
		)
		(pad "2" smd circle
			(at 0.40005 0)
			(size 0 0)
			(layers "F.Cu" "F.Mask" "F.Paste")
			(net "GND")
		)
	)
	(footprint ""
		(layer "F.Cu")
		(at 277.352252 -113.31067)
		(property "Reference" "R3536"
			(at 0 0 0)
			(layer "F.SilkS")
			(hide yes)
			(effects
				(font
					(size 1.27 1.27)
				)
			)
		)
		(property "Value" ""
			(at 0 0 0)
			(layer "F.Fab")
			(effects
				(font
					(size 1.27 1.27)
				)
			)
		)
		(duplicate_pad_numbers_are_jumpers no)
		(fp_line
			(start -0.7874 -0.4064)
			(end 0.7874 -0.4064)
			(stroke
				(width 0.1524)
				(type default)
			)
			(layer "F.SilkS")
		)
		(fp_line
			(start -0.7874 0.4064)
			(end -0.7874 -0.4064)
			(stroke
				(width 0.1524)
				(type default)
			)
			(layer "F.SilkS")
		)
		(fp_line
			(start 0.7874 -0.4064)
			(end 0.7874 0.4064)
			(stroke
				(width 0.1524)
				(type default)
			)
			(layer "F.SilkS")
		)
		(fp_line
			(start 0.7874 0.4064)
			(end -0.7874 0.4064)
			(stroke
				(width 0.1524)
				(type default)
			)
			(layer "F.SilkS")
		)
		(fp_line
			(start -0.67945 -0.305054)
			(end -0.12065 -0.305054)
			(stroke
				(width 0.1)
				(type default)
			)
			(layer "F.Fab")
		)
		(fp_line
			(start -0.67945 0.3048)
			(end -0.67945 -0.305054)
			(stroke
				(width 0.1)
				(type default)
			)
			(layer "F.Fab")
		)
		(fp_line
			(start -0.12065 -0.305054)
			(end -0.12065 -0.2794)
			(stroke
				(width 0.1)
				(type default)
			)
			(layer "F.Fab")
		)
		(fp_line
			(start -0.12065 -0.2794)
			(end 0.12065 -0.2794)
			(stroke
				(width 0.1)
				(type default)
			)
			(layer "F.Fab")
		)
		(fp_line
			(start -0.12065 0.2794)
			(end -0.12065 0.3048)
			(stroke
				(width 0.1)
				(type default)
			)
			(layer "F.Fab")
		)
		(fp_line
			(start -0.12065 0.3048)
			(end -0.67945 0.3048)
			(stroke
				(width 0.1)
				(type default)
			)
			(layer "F.Fab")
		)
		(fp_line
			(start 0.120396 0.2794)
			(end -0.12065 0.2794)
			(stroke
				(width 0.1)
				(type default)
			)
			(layer "F.Fab")
		)
		(fp_line
			(start 0.120396 0.3048)
			(end 0.120396 0.2794)
			(stroke
				(width 0.1)
				(type default)
			)
			(layer "F.Fab")
		)
		(fp_line
			(start 0.12065 -0.3048)
			(end 0.67945 -0.3048)
			(stroke
				(width 0.1)
				(type default)
			)
			(layer "F.Fab")
		)
		(fp_line
			(start 0.12065 -0.2794)
			(end 0.12065 -0.3048)
			(stroke
				(width 0.1)
				(type default)
			)
			(layer "F.Fab")
		)
		(fp_line
			(start 0.67945 -0.3048)
			(end 0.67945 0.3048)
			(stroke
				(width 0.1)
				(type default)
			)
			(layer "F.Fab")
		)
		(fp_line
			(start 0.67945 0.3048)
			(end 0.120396 0.3048)
			(stroke
				(width 0.1)
				(type default)
			)
			(layer "F.Fab")
		)
		(pad "1" smd circle
			(at -0.40005 0)
			(size 0 0)
			(layers "F.Cu" "F.Mask" "F.Paste")
			(net "P3V3_AUX")
		)
		(pad "2" smd circle
			(at 0.40005 0)
			(size 0 0)
			(layers "F.Cu" "F.Mask" "F.Paste")
			(net "SMB_SENSOR_E1S_3V3AUX_SDA")
		)
	)
)
